(kicad_pcb
	(version 20240108)
	(generator "pcbnew")
	(generator_version "8.0")
	(general
		(thickness 1.62)
		(legacy_teardrops no)
	)
	(paper "A4")
	(title_block
		(title "Jetson Orin Baseboard")
		(date "2025-03-12")
		(rev "1.3.4")
		(company "Antmicro Ltd")
		(comment 1 "www.antmicro.com")
		(comment 9 "footprints 636-639 of 677")
	)
	(layers
		(0 "F.Cu" signal)
		(1 "In1.Cu" signal)
		(2 "In2.Cu" signal)
		(3 "In3.Cu" signal)
		(4 "In4.Cu" jumper)
		(5 "In5.Cu" signal)
		(6 "In6.Cu" signal)
		(31 "B.Cu" signal)
		(32 "B.Adhes" user "B.Adhesive")
		(33 "F.Adhes" user "F.Adhesive")
		(34 "B.Paste" user)
		(35 "F.Paste" user)
		(36 "B.SilkS" user "B.Silkscreen")
		(37 "F.SilkS" user "F.Silkscreen")
		(38 "B.Mask" user)
		(39 "F.Mask" user)
		(40 "Dwgs.User" user "User.Drawings")
		(41 "Cmts.User" user "User.Comments")
		(42 "Eco1.User" user "User.Eco1")
		(43 "Eco2.User" user "User.Eco2")
		(44 "Edge.Cuts" user)
		(45 "Margin" user)
		(46 "B.CrtYd" user "B.Courtyard")
		(47 "F.CrtYd" user "F.Courtyard")
		(48 "B.Fab" user)
		(49 "F.Fab" user)
	)
	(footprint "antmicro-footprints:VQFN-HR-10_2x2mm"
		(layer "B.Cu")
		(at 52.875 81.075 -90)
		(property "Reference" "U48"
			(at -1.525 0.175 180)
			(layer "B.SilkS")
			(effects
				(font
					(size 0.7 0.7)
					(thickness 0.15)
				)
				(justify left bottom mirror)
			)
		)
		(property "Value" "TPS259474"
			(at 0 -2.8 90)
			(layer "B.Fab")
			(effects
				(font
					(size 0.7 0.7)
					(thickness 0.15)
				)
				(justify left bottom mirror)
			)
		)
		(property "Footprint" "antmicro-footprints:VQFN-HR-10_2x2mm"
			(at 0 0.045 90)
			(layer "B.Fab")
			(hide yes)
			(effects
				(font
					(size 1.27 1.27)
					(thickness 0.15)
				)
				(justify mirror)
			)
		)
		(property "Datasheet" "https://www.ti.com/lit/ds/symlink/tps25947.pdf"
			(at 0 0.045 90)
			(layer "B.Fab")
			(hide yes)
			(effects
				(font
					(size 1.27 1.27)
					(thickness 0.15)
				)
				(justify mirror)
			)
		)
		(property "Description" "Reverse Current Blocking eFuse with Input Reverse Polarity Protection, 5.5A, 23V, -40 to 125 Deg C, VQFN-HR-10"
			(at -0.05 -3.75 90)
			(layer "B.Fab")
			(hide yes)
			(effects
				(font
					(size 0.7 0.7)
					(thickness 0.15)
				)
				(justify mirror)
			)
		)
		(property "MPN" "TPS259474ARPWR"
			(at 0 0 90)
			(unlocked yes)
			(layer "B.Fab")
			(hide yes)
			(effects
				(font
					(size 1 1)
					(thickness 0.15)
				)
				(justify mirror)
			)
		)
		(property "Manufacturer" "Texas Instruments"
			(at 0 0 90)
			(unlocked yes)
			(layer "B.Fab")
			(hide yes)
			(effects
				(font
					(size 1 1)
					(thickness 0.15)
				)
				(justify mirror)
			)
		)
		(property "Author" "Antmicro"
			(at 0 0 90)
			(unlocked yes)
			(layer "B.Fab")
			(hide yes)
			(effects
				(font
					(size 1 1)
					(thickness 0.15)
				)
				(justify mirror)
			)
		)
		(property "License" "Apache-2.0"
			(at 0 0 90)
			(unlocked yes)
			(layer "B.Fab")
			(hide yes)
			(effects
				(font
					(size 1 1)
					(thickness 0.15)
				)
				(justify mirror)
			)
		)
		(sheetname "Supply")
		(sheetfile "supply.kicad_sch")
		(attr smd)
		(fp_circle
			(center -1.2 1.195)
			(end -1.15 1.195)
			(stroke
				(width 0.15)
				(type solid)
			)
			(fill solid)
			(layer "B.SilkS")
		)
		(fp_rect
			(start -1.45 1.45)
			(end 1.45 -1.45)
			(stroke
				(width 0.05)
				(type default)
			)
			(fill none)
			(layer "B.CrtYd")
		)
		(fp_line
			(start 1 1)
			(end -0.5 1)
			(stroke
				(width 0.1)
				(type default)
			)
			(layer "B.Fab")
		)
		(fp_line
			(start -1 0.5)
			(end -0.5 1)
			(stroke
				(width 0.1)
				(type default)
			)
			(layer "B.Fab")
		)
		(fp_line
			(start -1 0.5)
			(end -1 -1)
			(stroke
				(width 0.1)
				(type default)
			)
			(layer "B.Fab")
		)
		(fp_line
			(start -1 -1)
			(end 1 -1)
			(stroke
				(width 0.1)
				(type default)
			)
			(layer "B.Fab")
		)
		(fp_line
			(start 1 -1)
			(end 1 1)
			(stroke
				(width 0.1)
				(type default)
			)
			(layer "B.Fab")
		)
		(fp_text user "${REFERENCE}"
			(at -2.851 -5.45 90)
			(layer "B.Fab")
			(hide yes)
			(effects
				(font
					(size 0.7 0.7)
					(thickness 0.15)
				)
				(justify left bottom mirror)
			)
		)
		(fp_text user "Author: Antmicro"
			(at -2.851 -6.65 90)
			(layer "B.Fab")
			(hide yes)
			(effects
				(font
					(size 0.7 0.7)
					(thickness 0.15)
				)
				(justify left bottom mirror)
			)
		)
		(fp_text user "License: Apache-2.0"
			(at -2.851 -7.85 90)
			(layer "B.Fab")
			(hide yes)
			(effects
				(font
					(size 0.7 0.7)
					(thickness 0.15)
				)
				(justify left bottom mirror)
			)
		)
		(pad "" smd roundrect
			(at -0.9 -0.6875 270)
			(size 0.6 0.275)
			(layers "B.Paste")
			(roundrect_rratio 0.1818181818)
			(thermal_bridge_angle 45)
		)
		(pad "" smd roundrect
			(at -0.9 0.6875 270)
			(size 0.6 0.275)
			(layers "B.Paste")
			(roundrect_rratio 0.1818181818)
			(thermal_bridge_angle 45)
		)
		(pad "" smd roundrect
			(at -0.7125 -0.875 270)
			(size 0.225 0.65)
			(layers "B.Paste")
			(roundrect_rratio 0.2222222222)
			(thermal_bridge_angle 45)
		)
		(pad "" smd roundrect
			(at -0.7125 0.875 270)
			(size 0.225 0.65)
			(layers "B.Paste")
			(roundrect_rratio 0.2222222222)
			(thermal_bridge_angle 45)
		)
		(pad "" smd roundrect
			(at -0.25 -0.63 270)
			(size 0.28 1.06)
			(layers "B.Paste")
			(roundrect_rratio 0.1785714286)
			(thermal_bridge_angle 45)
		)
		(pad "" smd roundrect
			(at -0.25 0.63 270)
			(size 0.28 1.06)
			(layers "B.Paste")
			(roundrect_rratio 0.1785714286)
			(thermal_bridge_angle 45)
		)
		(pad "" smd roundrect
			(at 0.25 -0.63 270)
			(size 0.28 1.06)
			(layers "B.Paste")
			(roundrect_rratio 0.1785714286)
			(thermal_bridge_angle 45)
		)
		(pad "" smd roundrect
			(at 0.25 0.63 270)
			(size 0.28 1.06)
			(layers "B.Paste")
			(roundrect_rratio 0.1785714286)
			(thermal_bridge_angle 45)
		)
		(pad "" smd roundrect
			(at 0.7125 -0.875 270)
			(size 0.225 0.65)
			(layers "B.Paste")
			(roundrect_rratio 0.2222222222)
			(thermal_bridge_angle 45)
		)
		(pad "" smd roundrect
			(at 0.7125 0.875 270)
			(size 0.225 0.65)
			(layers "B.Paste")
			(roundrect_rratio 0.2222222222)
			(thermal_bridge_angle 45)
		)
		(pad "" smd roundrect
			(at 0.9 -0.6875 270)
			(size 0.6 0.275)
			(layers "B.Paste")
			(roundrect_rratio 0.1818181818)
			(thermal_bridge_angle 45)
		)
		(pad "" smd roundrect
			(at 0.9 0.6875 270)
			(size 0.6 0.275)
			(layers "B.Paste")
			(roundrect_rratio 0.1818181818)
			(thermal_bridge_angle 45)
		)
		(pad "1" smd roundrect
			(at -0.9 0.7 270)
			(size 0.6 0.3)
			(layers "B.Cu" "B.Mask")
			(roundrect_rratio 0.1666666667)
			(net 789 "MODULE_ID")
			(pinfunction "EN/UVLO")
			(pintype "input")
			(thermal_bridge_angle 45)
		)
		(pad "1" smd roundrect
			(at -0.725 0.875 90)
			(size 0.25 0.65)
			(layers "B.Cu" "B.Mask")
			(roundrect_rratio 0.2)
			(net 789 "MODULE_ID")
			(pinfunction "EN/UVLO")
			(pintype "input")
			(thermal_bridge_angle 45)
		)
		(pad "2" smd roundrect
			(at -0.9 0.225 270)
			(size 0.6 0.25)
			(layers "B.Cu" "B.Paste" "B.Mask")
			(roundrect_rratio 0.2)
			(net 1 "GND")
			(pinfunction "OVLO")
			(pintype "input")
			(thermal_bridge_angle 45)
		)
		(pad "3" smd roundrect
			(at -0.9 -0.225 270)
			(size 0.6 0.25)
			(layers "B.Cu" "B.Paste" "B.Mask")
			(roundrect_rratio 0.2)
			(net 799 "/Supply/PG_{HP}")
			(pinfunction "PG")
			(pintype "output")
			(thermal_bridge_angle 45)
		)
		(pad "4" smd roundrect
			(at -0.9 -0.7 270)
			(size 0.6 0.3)
			(layers "B.Cu" "B.Mask")
			(roundrect_rratio 0.1666666667)
			(net 789 "MODULE_ID")
			(pinfunction "PGTH")
			(pintype "input")
			(thermal_bridge_angle 45)
		)
		(pad "4" smd roundrect
			(at -0.725 -0.875 90)
			(size 0.25 0.65)
			(layers "B.Cu" "B.Mask")
			(roundrect_rratio 0.2)
			(net 789 "MODULE_ID")
			(pinfunction "PGTH")
			(pintype "input")
			(thermal_bridge_angle 45)
		)
		(pad "5" smd roundrect
			(at -0.25 0 270)
			(size 0.3 2.4)
			(layers "B.Cu" "B.Mask")
			(roundrect_rratio 0.25)
			(net 115 "VCC")
			(pinfunction "IN")
			(pintype "power_in")
			(thermal_bridge_angle 45)
		)
		(pad "6" smd roundrect
			(at 0.25 0 270)
			(size 0.3 2.4)
			(layers "B.Cu" "B.Mask")
			(roundrect_rratio 0.25)
			(net 788 "VDD_SoM")
			(pinfunction "OUT")
			(pintype "power_out")
			(thermal_bridge_angle 45)
		)
		(pad "7" smd roundrect
			(at 0.725 -0.875 90)
			(size 0.25 0.65)
			(layers "B.Cu" "B.Mask")
			(roundrect_rratio 0.2)
			(net 644 "Net-(U48-DVDT)")
			(pinfunction "DVDT")
			(pintype "output")
			(thermal_bridge_angle 45)
		)
		(pad "7" smd roundrect
			(at 0.9 -0.7 90)
			(size 0.6 0.3)
			(layers "B.Cu" "B.Mask")
			(roundrect_rratio 0.1666666667)
			(net 644 "Net-(U48-DVDT)")
			(pinfunction "DVDT")
			(pintype "output")
			(thermal_bridge_angle 45)
		)
		(pad "8" smd roundrect
			(at 0.9 -0.225 90)
			(size 0.6 0.25)
			(layers "B.Cu" "B.Paste" "B.Mask")
			(roundrect_rratio 0.2)
			(net 1 "GND")
			(pinfunction "GND")
			(pintype "power_in")
			(thermal_bridge_angle 45)
		)
		(pad "9" smd roundrect
			(at 0.9 0.225 90)
			(size 0.6 0.25)
			(layers "B.Cu" "B.Paste" "B.Mask")
			(roundrect_rratio 0.2)
			(net 791 "Net-(U48-ILIM)")
			(pinfunction "ILIM")
			(pintype "output")
			(thermal_bridge_angle 45)
		)
		(pad "10" smd roundrect
			(at 0.725 0.875 90)
			(size 0.25 0.65)
			(layers "B.Cu" "B.Mask")
			(roundrect_rratio 0.2)
			(net 797 "unconnected-(U48-ITIMER-Pad10)_1")
			(pinfunction "ITIMER")
			(pintype "output+no_connect")
			(thermal_bridge_angle 45)
		)
		(pad "10" smd roundrect
			(at 0.9 0.7 90)
			(size 0.6 0.3)
			(layers "B.Cu" "B.Mask")
			(roundrect_rratio 0.1666666667)
			(net 796 "unconnected-(U48-ITIMER-Pad10)")
			(pinfunction "ITIMER")
			(pintype "output+no_connect")
			(thermal_bridge_angle 45)
		)
	)
	(footprint "antmicro-footprints:TP_SMD_0.75mm"
		(layer "B.Cu")
		(at 111.9 104.1)
		(property "Reference" "TP32"
			(at 3.01 0.39 180)
			(layer "B.SilkS")
			(effects
				(font
					(size 0.7 0.7)
					(thickness 0.15)
				)
				(justify left bottom mirror)
			)
		)
		(property "Value" "TP_0.75mm_SMD"
			(at 0 -1.2 180)
			(layer "B.Fab")
			(effects
				(font
					(size 0.7 0.7)
					(thickness 0.15)
				)
				(justify left bottom mirror)
			)
		)
		(property "Footprint" "antmicro-footprints:TP_SMD_0.75mm"
			(at 0 0 0)
			(layer "F.Fab")
			(hide yes)
			(effects
				(font
					(size 1.27 1.27)
					(thickness 0.15)
				)
			)
		)
		(property "Author" "Antmicro"
			(at 0 0 0)
			(layer "B.Fab")
			(hide yes)
			(effects
				(font
					(size 1 1)
					(thickness 0.15)
				)
				(justify mirror)
			)
		)
		(property "License" "Apache-2.0"
			(at 0 0 0)
			(layer "B.Fab")
			(hide yes)
			(effects
				(font
					(size 1 1)
					(thickness 0.15)
				)
				(justify mirror)
			)
		)
		(property "MPN" ""
			(at 0 0 0)
			(layer "B.Fab")
			(hide yes)
			(effects
				(font
					(size 1 1)
					(thickness 0.15)
				)
				(justify mirror)
			)
		)
		(property "Manufacturer" ""
			(at 0 0 0)
			(layer "B.Fab")
			(hide yes)
			(effects
				(font
					(size 1 1)
					(thickness 0.15)
				)
				(justify mirror)
			)
		)
		(sheetname "USB3")
		(sheetfile "usb3.kicad_sch")
		(attr exclude_from_pos_files exclude_from_bom)
		(fp_circle
			(center 0 0)
			(end 0.475 0)
			(stroke
				(width 0.05)
				(type default)
			)
			(fill none)
			(layer "B.CrtYd")
		)
		(fp_text user "${REFERENCE}"
			(at -0.4 -2.7 180)
			(layer "B.Fab")
			(hide yes)
			(effects
				(font
					(size 0.7 0.7)
					(thickness 0.15)
				)
				(justify left bottom mirror)
			)
		)
		(fp_text user "License: Apache-2.0"
			(at -0.4 -5.101 180)
			(layer "B.Fab")
			(hide yes)
			(effects
				(font
					(size 0.7 0.7)
					(thickness 0.15)
				)
				(justify left bottom mirror)
			)
		)
		(fp_text user "Author: Antmicro"
			(at -0.4 -3.901 180)
			(layer "B.Fab")
			(hide yes)
			(effects
				(font
					(size 0.7 0.7)
					(thickness 0.15)
				)
				(justify left bottom mirror)
			)
		)
		(pad "1" smd circle
			(at 0 0)
			(size 0.75 0.75)
			(layers "B.Cu" "B.Mask")
			(net 391 "/USB3/USBC1_FAULT_N")
			(pinfunction "1")
			(pintype "passive")
		)
	)
	(footprint "antmicro-footprints:SOD-923"
		(layer "B.Cu")
		(at 63.58 84.14 180)
		(property "Reference" "D31"
			(at -2.87 -0.4 0)
			(unlocked yes)
			(layer "B.SilkS")
			(effects
				(font
					(size 0.7 0.7)
					(thickness 0.15)
				)
				(justify left bottom mirror)
			)
		)
		(property "Value" "ESD9X5.0ST5G"
			(at 0 -1.3 0)
			(unlocked yes)
			(layer "B.Fab")
			(effects
				(font
					(size 0.7 0.7)
					(thickness 0.15)
				)
				(justify left bottom mirror)
			)
		)
		(property "Footprint" "antmicro-footprints:SOD-923"
			(at 0 0 180)
			(layer "F.Fab")
			(hide yes)
			(effects
				(font
					(size 1.27 1.27)
					(thickness 0.15)
				)
			)
		)
		(property "Datasheet" "https://www.onsemi.com/pdf/datasheet/esd9x3.3st5g-d.pdf"
			(at 0 0 180)
			(layer "F.Fab")
			(hide yes)
			(effects
				(font
					(size 1.27 1.27)
					(thickness 0.15)
				)
			)
		)
		(property "Author" "Antmicro"
			(at 127.16 168.28 0)
			(layer "B.Fab")
			(hide yes)
			(effects
				(font
					(size 1 1)
					(thickness 0.15)
				)
				(justify mirror)
			)
		)
		(property "License" "Apache-2.0"
			(at 127.16 168.28 0)
			(layer "B.Fab")
			(hide yes)
			(effects
				(font
					(size 1 1)
					(thickness 0.15)
				)
				(justify mirror)
			)
		)
		(property "MPN" "ESD9X5.0ST5G"
			(at 127.16 168.28 0)
			(layer "B.Fab")
			(hide yes)
			(effects
				(font
					(size 1 1)
					(thickness 0.15)
				)
				(justify mirror)
			)
		)
		(property "Manufacturer" "ON Semiconductor"
			(at 127.16 168.28 0)
			(layer "B.Fab")
			(hide yes)
			(effects
				(font
					(size 1 1)
					(thickness 0.15)
				)
				(justify mirror)
			)
		)
		(sheetname "Supply")
		(sheetfile "supply.kicad_sch")
		(attr smd)
		(fp_line
			(start 0.5 0.4)
			(end -0.5 0.4)
			(stroke
				(width 0.15)
				(type solid)
			)
			(layer "B.SilkS")
		)
		(fp_line
			(start 0.5 0.3)
			(end 0.5 0.4)
			(stroke
				(width 0.15)
				(type solid)
			)
			(layer "B.SilkS")
		)
		(fp_line
			(start 0.5 -0.3)
			(end 0.5 -0.4)
			(stroke
				(width 0.15)
				(type solid)
			)
			(layer "B.SilkS")
		)
		(fp_line
			(start 0.5 -0.4)
			(end -0.5 -0.4)
			(stroke
				(width 0.15)
				(type solid)
			)
			(layer "B.SilkS")
		)
		(fp_line
			(start -0.16 -0.4)
			(end -0.16 0.4)
			(stroke
				(width 0.15)
				(type solid)
			)
			(layer "B.SilkS")
		)
		(fp_line
			(start -0.5 0.4)
			(end -0.5 0.3)
			(stroke
				(width 0.15)
				(type solid)
			)
			(layer "B.SilkS")
		)
		(fp_line
			(start -0.5 -0.3)
			(end -0.5 -0.4)
			(stroke
				(width 0.15)
				(type solid)
			)
			(layer "B.SilkS")
		)
		(fp_rect
			(start -0.68 0.41)
			(end 0.68 -0.41)
			(stroke
				(width 0.05)
				(type solid)
			)
			(fill none)
			(layer "B.CrtYd")
		)
		(fp_line
			(start -0.202 -0.298)
			(end -0.202 0.3)
			(stroke
				(width 0.15)
				(type solid)
			)
			(layer "B.Fab")
		)
		(fp_rect
			(start -0.402 0.3)
			(end 0.4 -0.298)
			(stroke
				(width 0.15)
				(type solid)
			)
			(fill none)
			(layer "B.Fab")
		)
		(fp_text user "License: Apache-2.0"
			(at -0.68 -4.5 0)
			(layer "B.Fab")
			(hide yes)
			(effects
				(font
					(size 0.7 0.7)
					(thickness 0.15)
				)
				(justify left bottom mirror)
			)
		)
		(fp_text user "Author: Antmicro"
			(at -0.68 -5.7 0)
			(layer "B.Fab")
			(hide yes)
			(effects
				(font
					(size 0.7 0.7)
					(thickness 0.15)
				)
				(justify left bottom mirror)
			)
		)
		(fp_text user "${REFERENCE}"
			(at -0.68 -3.3 0)
			(unlocked yes)
			(layer "B.Fab")
			(hide yes)
			(effects
				(font
					(size 0.7 0.7)
					(thickness 0.15)
				)
				(justify left bottom mirror)
			)
		)
		(pad "1" smd roundrect
			(at -0.438 0 180)
			(size 0.4 0.325)
			(layers "B.Cu" "B.Paste" "B.Mask")
			(roundrect_rratio 0.25)
			(net 112 "+1V8")
			(pinfunction "C")
			(pintype "passive")
		)
		(pad "2" smd roundrect
			(at 0.436 0 180)
			(size 0.4 0.325)
			(layers "B.Cu" "B.Paste" "B.Mask")
			(roundrect_rratio 0.25)
			(net 1 "GND")
			(pinfunction "A")
			(pintype "passive")
		)
	)
	(footprint "antmicro-footprints:C_0402_1005Metric"
		(layer "B.Cu")
		(at 66.46 81.31 180)
		(descr "Capacitor SMD 0402")
		(tags "capacitor SMD 0402")
		(property "Reference" "C40"
			(at -1.09 -1.34 0)
			(layer "B.SilkS")
			(effects
				(font
					(size 0.7 0.7)
					(thickness 0.15)
				)
				(justify left bottom mirror)
			)
		)
		(property "Value" "C_100n_0402"
			(at 0 -1.4 0)
			(layer "B.Fab")
			(effects
				(font
					(size 0.7 0.7)
					(thickness 0.15)
				)
				(justify left bottom mirror)
			)
		)
		(property "Footprint" "antmicro-footprints:C_0402_1005Metric"
			(at 0 0 180)
			(layer "F.Fab")
			(hide yes)
			(effects
				(font
					(size 1.27 1.27)
					(thickness 0.15)
				)
			)
		)
		(property "Datasheet" "https://www.murata.com/products/productdetail?partno=GRM155R61H104KE14%23"
			(at 0 0 180)
			(layer "F.Fab")
			(hide yes)
			(effects
				(font
					(size 1.27 1.27)
					(thickness 0.15)
				)
			)
		)
		(property "Author" "Antmicro"
			(at 132.92 162.62 0)
			(layer "B.Fab")
			(hide yes)
			(effects
				(font
					(size 1 1)
					(thickness 0.15)
				)
				(justify mirror)
			)
		)
		(property "Dielectric" "X5R"
			(at 132.92 162.62 0)
			(layer "B.Fab")
			(hide yes)
			(effects
				(font
					(size 1 1)
					(thickness 0.15)
				)
				(justify mirror)
			)
		)
		(property "License" "Apache-2.0"
			(at 132.92 162.62 0)
			(layer "B.Fab")
			(hide yes)
			(effects
				(font
					(size 1 1)
					(thickness 0.15)
				)
				(justify mirror)
			)
		)
		(property "MPN" "GRM155R61H104KE14D"
			(at 132.92 162.62 0)
			(layer "B.Fab")
			(hide yes)
			(effects
				(font
					(size 1 1)
					(thickness 0.15)
				)
				(justify mirror)
			)
		)
		(property "Manufacturer" "Murata"
			(at 132.92 162.62 0)
			(layer "B.Fab")
			(hide yes)
			(effects
				(font
					(size 1 1)
					(thickness 0.15)
				)
				(justify mirror)
			)
		)
		(property "Val" "100n"
			(at 132.92 162.62 0)
			(layer "B.Fab")
			(hide yes)
			(effects
				(font
					(size 1 1)
					(thickness 0.15)
				)
				(justify mirror)
			)
		)
		(property "Voltage" "50V"
			(at 132.92 162.62 0)
			(layer "B.Fab")
			(hide yes)
			(effects
				(font
					(size 1 1)
					(thickness 0.15)
				)
				(justify mirror)
			)
		)
		(sheetname "SoM")
		(sheetfile "som.kicad_sch")
		(attr smd)
		(fp_rect
			(start -0.925 0.47)
			(end 0.925 -0.47)
			(stroke
				(width 0.05)
				(type default)
			)
			(fill none)
			(layer "B.CrtYd")
		)
		(fp_line
			(start 0.504 0.25)
			(end -0.494 0.25)
			(stroke
				(width 0.15)
				(type solid)
			)
			(layer "B.Fab")
		)
		(fp_line
			(start 0.504 -0.248)
			(end 0.504 0.25)
			(stroke
				(width 0.15)
				(type solid)
			)
			(layer "B.Fab")
		)
		(fp_line
			(start -0.494 0.25)
			(end -0.494 -0.248)
			(stroke
				(width 0.15)
				(type solid)
			)
			(layer "B.Fab")
		)
		(fp_line
			(start -0.494 -0.248)
			(end 0.504 -0.248)
			(stroke
				(width 0.15)
				(type solid)
			)
			(layer "B.Fab")
		)
		(fp_text user "License: Apache-2.0"
			(at -0.932 -5.17 0)
			(layer "B.Fab")
			(hide yes)
			(effects
				(font
					(size 0.7 0.7)
					(thickness 0.15)
				)
				(justify left bottom mirror)
			)
		)
		(fp_text user "Author: Antmicro"
			(at -0.932 -4.17 0)
			(layer "B.Fab")
			(hide yes)
			(effects
				(font
					(size 0.7 0.7)
					(thickness 0.15)
				)
				(justify left bottom mirror)
			)
		)
		(fp_text user "${REFERENCE}"
			(at -0.932 -3.168 0)
			(layer "B.Fab")
			(hide yes)
			(effects
				(font
					(size 0.7 0.7)
					(thickness 0.15)
				)
				(justify left bottom mirror)
			)
		)
		(pad "1" smd roundrect
			(at -0.48 0 180)
			(size 0.59 0.64)
			(layers "B.Cu" "B.Paste" "B.Mask")
			(roundrect_rratio 0.25)
			(net 1 "GND")
			(pintype "passive")
		)
		(pad "2" smd roundrect
			(at 0.48 0 180)
			(size 0.59 0.64)
			(layers "B.Cu" "B.Paste" "B.Mask")
			(roundrect_rratio 0.25)
			(net 112 "+1V8")
			(pintype "passive")
		)
	)
)
